(kicad_pcb
	(version 20260206)
	(generator "pcbnew")
	(generator_version "10.0")
	(general
		(thickness 1.6)
		(legacy_teardrops no)
	)
	(paper "A4")
	(title_block
		(title "Bryce Canyon_IOM_IOC_16318-2_OCP.brd")
		(comment 1 "Bryce Canyon / footprints 316-323 of 1605")
	)
	(layers
		(0 "F.Cu" signal "TOP")
		(4 "In1.Cu" signal "L2GND")
		(6 "In2.Cu" signal "L3")
		(8 "In3.Cu" signal "L4VCC")
		(10 "In4.Cu" signal "L5VCC")
		(12 "In5.Cu" signal "L6")
		(14 "In6.Cu" signal "L7GND")
		(2 "B.Cu" signal "BOTTOM")
		(9 "F.Adhes" user "F.Adhesive")
		(11 "B.Adhes" user "B.Adhesive")
		(13 "F.Paste" user "Package Geometry/Pastemask Top")
		(15 "B.Paste" user "Package Geometry/Pastemask Bottom")
		(5 "F.SilkS" user "Ref Des/Silkscreen Top")
		(7 "B.SilkS" user "Ref Des/Silkscreen Bottom")
		(1 "F.Mask" user "Board Geometry/Soldermask Top")
		(3 "B.Mask" user "Board Geometry/Soldermask Bottom")
		(17 "Dwgs.User" user "User.Drawings")
		(19 "Cmts.User" user "User.Comments")
		(21 "Eco1.User" user "User.Eco1")
		(23 "Eco2.User" user "User.Eco2")
		(25 "Edge.Cuts" user "Board Geometry/Outline")
		(27 "Margin" user)
		(31 "F.CrtYd" user "Package Geometry/Place Bound Top")
		(29 "B.CrtYd" user "Package Geometry/Place Bound Bottom")
		(35 "F.Fab" user "Ref Des/Assembly Top")
		(33 "B.Fab" user "Ref Des/Assembly Bottom")
	)
	(footprint ""
		(layer "F.Cu")
		(at 199.2376 -25.654)
		(property "Reference" "R695"
			(at 0 0 0)
			(layer "F.SilkS")
			(hide yes)
			(effects
				(font
					(size 1.27 1.27)
				)
			)
		)
		(property "Value" "1KR2F-3-GP"
			(at 0.064008 -3.993896 0)
			(unlocked yes)
			(layer "F.Fab")
			(hide yes)
			(effects
				(font
					(size 1.016 1.016)
					(thickness 0.1524)
				)
			)
		)
		(property "Device Type" "R402H16"
			(at 0.064008 -5.517896 0)
			(unlocked yes)
			(layer "F.Fab")
			(hide yes)
			(effects
				(font
					(size 1.016 1.016)
					(thickness 0.1524)
				)
			)
		)
		(duplicate_pad_numbers_are_jumpers no)
		(fp_line
			(start -0.508 -0.9398)
			(end -0.508 0.9398)
			(stroke
				(width 0.1524)
				(type default)
			)
			(layer "F.SilkS")
		)
		(fp_line
			(start 0.508 -0.9398)
			(end -0.508 -0.9398)
			(stroke
				(width 0.1524)
				(type default)
			)
			(layer "F.SilkS")
		)
		(fp_rect
			(start -0.508 0.9398)
			(end 0.508 -0.9398)
			(stroke
				(width 0)
				(type default)
			)
			(fill no)
			(layer "F.CrtYd")
		)
		(fp_rect
			(start -0.508 0.9398)
			(end 0.508 -0.9398)
			(stroke
				(width 0)
				(type default)
			)
			(fill no)
			(layer "F.Fab")
		)
		(pad "1" smd custom
			(at 0 -0.4445)
			(size 0.1397 0.1397)
			(layers "F.Cu" "F.Mask" "F.Paste")
			(net "P5V_STBY")
			(options
				(clearance outline)
				(anchor circle)
			)
			(primitives
				(gr_poly
					(pts
						(arc
							(start -0.1778 -0.2794)
							(mid -0.249642 -0.249642)
							(end -0.2794 -0.1778)
						)
						(arc
							(start -0.2794 0.1778)
							(mid -0.249642 0.249642)
							(end -0.1778 0.2794)
						)
						(arc
							(start 0.1778 0.2794)
							(mid 0.249642 0.249642)
							(end 0.2794 0.1778)
						)
						(arc
							(start 0.2794 -0.1778)
							(mid 0.249642 -0.249642)
							(end 0.1778 -0.2794)
						)
					)
					(width 0)
					(fill yes)
				)
			)
		)
		(pad "2" smd custom
			(at 0 0.4445)
			(size 0.1397 0.1397)
			(layers "F.Cu" "F.Mask" "F.Paste")
			(net "EXT1_LED_BLUE_G2")
			(options
				(clearance outline)
				(anchor circle)
			)
			(primitives
				(gr_poly
					(pts
						(arc
							(start -0.1778 -0.2794)
							(mid -0.249642 -0.249642)
							(end -0.2794 -0.1778)
						)
						(arc
							(start -0.2794 0.1778)
							(mid -0.249642 0.249642)
							(end -0.1778 0.2794)
						)
						(arc
							(start 0.1778 0.2794)
							(mid 0.249642 0.249642)
							(end 0.2794 0.1778)
						)
						(arc
							(start 0.2794 -0.1778)
							(mid 0.249642 -0.249642)
							(end 0.1778 -0.2794)
						)
					)
					(width 0)
					(fill yes)
				)
			)
		)
	)
	(footprint ""
		(layer "F.Cu")
		(at 181.95163 -154.96286 180)
		(property "Reference" "R713"
			(at 0 0 180)
			(layer "F.SilkS")
			(hide yes)
			(effects
				(font
					(size 1.27 1.27)
				)
			)
		)
		(property "Value" "0R2J-2-GP"
			(at 0.064008 -3.993896 180)
			(unlocked yes)
			(layer "F.Fab")
			(hide yes)
			(effects
				(font
					(size 1.016 1.016)
					(thickness 0.1524)
				)
			)
		)
		(property "Device Type" "R402H16"
			(at 0.064008 -5.517896 180)
			(unlocked yes)
			(layer "F.Fab")
			(hide yes)
			(effects
				(font
					(size 1.016 1.016)
					(thickness 0.1524)
				)
			)
		)
		(duplicate_pad_numbers_are_jumpers no)
		(fp_line
			(start 0.508 -0.9398)
			(end -0.508 -0.9398)
			(stroke
				(width 0.1524)
				(type default)
			)
			(layer "F.SilkS")
		)
		(fp_line
			(start -0.508 -0.9398)
			(end -0.508 0.9398)
			(stroke
				(width 0.1524)
				(type default)
			)
			(layer "F.SilkS")
		)
		(fp_rect
			(start -0.508 0.9398)
			(end 0.508 -0.9398)
			(stroke
				(width 0)
				(type default)
			)
			(fill no)
			(layer "F.CrtYd")
		)
		(fp_rect
			(start -0.508 0.9398)
			(end 0.508 -0.9398)
			(stroke
				(width 0)
				(type default)
			)
			(fill no)
			(layer "F.Fab")
		)
		(pad "1" smd custom
			(at 0 -0.4445 180)
			(size 0.1397 0.1397)
			(layers "F.Cu" "F.Mask" "F.Paste")
			(net "P5V_EN_R")
			(options
				(clearance outline)
				(anchor circle)
			)
			(primitives
				(gr_poly
					(pts
						(arc
							(start -0.1778 -0.2794)
							(mid -0.249642 -0.249642)
							(end -0.2794 -0.1778)
						)
						(arc
							(start -0.2794 0.1778)
							(mid -0.249642 0.249642)
							(end -0.1778 0.2794)
						)
						(arc
							(start 0.1778 0.2794)
							(mid 0.249642 0.249642)
							(end 0.2794 0.1778)
						)
						(arc
							(start 0.2794 -0.1778)
							(mid 0.249642 -0.249642)
							(end 0.1778 -0.2794)
						)
					)
					(width 0)
					(fill yes)
				)
			)
		)
		(pad "2" smd custom
			(at 0 0.4445 180)
			(size 0.1397 0.1397)
			(layers "F.Cu" "F.Mask" "F.Paste")
			(net "P12V_IOM_PGOOD")
			(options
				(clearance outline)
				(anchor circle)
			)
			(primitives
				(gr_poly
					(pts
						(arc
							(start -0.1778 -0.2794)
							(mid -0.249642 -0.249642)
							(end -0.2794 -0.1778)
						)
						(arc
							(start -0.2794 0.1778)
							(mid -0.249642 0.249642)
							(end -0.1778 0.2794)
						)
						(arc
							(start 0.1778 0.2794)
							(mid 0.249642 0.249642)
							(end 0.2794 0.1778)
						)
						(arc
							(start 0.2794 -0.1778)
							(mid 0.249642 -0.249642)
							(end 0.1778 -0.2794)
						)
					)
					(width 0)
					(fill yes)
				)
			)
		)
	)
	(footprint ""
		(layer "F.Cu")
		(at 68.8086 -170.7642 180)
		(property "Reference" "R332"
			(at 0 0 180)
			(layer "F.SilkS")
			(hide yes)
			(effects
				(font
					(size 1.27 1.27)
				)
			)
		)
		(property "Value" "4K7R2F-GP"
			(at 0.064008 -3.993896 180)
			(unlocked yes)
			(layer "F.Fab")
			(hide yes)
			(effects
				(font
					(size 1.016 1.016)
					(thickness 0.1524)
				)
			)
		)
		(property "Device Type" "R402H16"
			(at 0.064008 -5.517896 180)
			(unlocked yes)
			(layer "F.Fab")
			(hide yes)
			(effects
				(font
					(size 1.016 1.016)
					(thickness 0.1524)
				)
			)
		)
		(duplicate_pad_numbers_are_jumpers no)
		(fp_line
			(start 0.508 -0.9398)
			(end -0.508 -0.9398)
			(stroke
				(width 0.1524)
				(type default)
			)
			(layer "F.SilkS")
		)
		(fp_line
			(start -0.508 -0.9398)
			(end -0.508 0.9398)
			(stroke
				(width 0.1524)
				(type default)
			)
			(layer "F.SilkS")
		)
		(fp_rect
			(start -0.508 0.9398)
			(end 0.508 -0.9398)
			(stroke
				(width 0)
				(type default)
			)
			(fill no)
			(layer "F.CrtYd")
		)
		(fp_rect
			(start -0.508 0.9398)
			(end 0.508 -0.9398)
			(stroke
				(width 0)
				(type default)
			)
			(fill no)
			(layer "F.Fab")
		)
		(pad "1" smd custom
			(at 0 -0.4445 180)
			(size 0.1397 0.1397)
			(layers "F.Cu" "F.Mask" "F.Paste")
			(net "P3V3_STBY")
			(options
				(clearance outline)
				(anchor circle)
			)
			(primitives
				(gr_poly
					(pts
						(arc
							(start -0.1778 -0.2794)
							(mid -0.249642 -0.249642)
							(end -0.2794 -0.1778)
						)
						(arc
							(start -0.2794 0.1778)
							(mid -0.249642 0.249642)
							(end -0.1778 0.2794)
						)
						(arc
							(start 0.1778 0.2794)
							(mid 0.249642 0.249642)
							(end 0.2794 0.1778)
						)
						(arc
							(start 0.2794 -0.1778)
							(mid 0.249642 -0.249642)
							(end 0.1778 -0.2794)
						)
					)
					(width 0)
					(fill yes)
				)
			)
		)
		(pad "2" smd custom
			(at 0 0.4445 180)
			(size 0.1397 0.1397)
			(layers "F.Cu" "F.Mask" "F.Paste")
			(net "COMP_TO_BMC_RESET_N_OUT")
			(options
				(clearance outline)
				(anchor circle)
			)
			(primitives
				(gr_poly
					(pts
						(arc
							(start -0.1778 -0.2794)
							(mid -0.249642 -0.249642)
							(end -0.2794 -0.1778)
						)
						(arc
							(start -0.2794 0.1778)
							(mid -0.249642 0.249642)
							(end -0.1778 0.2794)
						)
						(arc
							(start 0.1778 0.2794)
							(mid 0.249642 0.249642)
							(end 0.2794 0.1778)
						)
						(arc
							(start 0.2794 -0.1778)
							(mid 0.249642 -0.249642)
							(end 0.1778 -0.2794)
						)
					)
					(width 0)
					(fill yes)
				)
			)
		)
	)
	(footprint ""
		(layer "F.Cu")
		(at 87.619332 -27.578812 180)
		(property "Reference" "D13"
			(at 0 0 180)
			(layer "F.SilkS")
			(hide yes)
			(effects
				(font
					(size 1.27 1.27)
				)
			)
		)
		(property "Value" "PESD5V0S1BL-1-GP"
			(at 1.8923 -1.5621 180)
			(unlocked yes)
			(layer "F.Fab")
			(hide yes)
			(effects
				(font
					(size 1.016 1.016)
					(thickness 0.1524)
				)
			)
		)
		(property "Device Type" "SOD882-10D6-1H20"
			(at 1.8923 -3.0861 180)
			(unlocked yes)
			(layer "F.Fab")
			(hide yes)
			(effects
				(font
					(size 1.016 1.016)
					(thickness 0.1524)
				)
			)
		)
		(duplicate_pad_numbers_are_jumpers no)
		(fp_line
			(start -0.3048 -0.9271)
			(end 0.3048 -0.9271)
			(stroke
				(width 0.254)
				(type default)
			)
			(layer "F.SilkS")
		)
		(fp_rect
			(start -0.2921 0.4953)
			(end 0.2921 -0.4953)
			(stroke
				(width 0)
				(type default)
			)
			(fill no)
			(layer "F.CrtYd")
		)
		(fp_poly
			(pts
				(xy -0.4318 0.8001) (xy -0.4318 -0.266192) (xy -0.2921 -0.266192) (xy -0.2921 0.4953) (xy 0.2921 0.4953)
				(xy 0.2921 -0.4953) (xy -0.2921 -0.4953) (xy -0.2921 -0.2667) (xy -0.4318 -0.2667) (xy -0.4318 -0.8001)
				(xy 0.4318 -0.8001) (xy 0.4318 0.8001)
			)
			(stroke
				(width 0)
				(type default)
			)
			(fill no)
			(layer "F.CrtYd")
		)
		(fp_rect
			(start -0.4318 0.8001)
			(end 0.4318 -0.8001)
			(stroke
				(width 0)
				(type default)
			)
			(fill no)
			(layer "F.Fab")
		)
		(pad "1" smd custom
			(at 0 -0.4445 180)
			(size 0.1143 0.1143)
			(layers "F.Cu" "F.Mask" "F.Paste")
			(net "P5V_VBUS_CONN")
			(options
				(clearance outline)
				(anchor circle)
			)
			(primitives
				(gr_poly
					(pts
						(arc
							(start -0.2032 0.2286)
							(mid -0.275042 0.198842)
							(end -0.3048 0.127)
						)
						(arc
							(start -0.3048 -0.127)
							(mid -0.275042 -0.198842)
							(end -0.2032 -0.2286)
						)
						(arc
							(start 0.2032 -0.2286)
							(mid 0.275042 -0.198842)
							(end 0.3048 -0.127)
						)
						(arc
							(start 0.3048 0.127)
							(mid 0.275042 0.198842)
							(end 0.2032 0.2286)
						)
					)
					(width 0)
					(fill yes)
				)
			)
		)
		(pad "2" smd custom
			(at 0 0.4445 180)
			(size 0.1143 0.1143)
			(layers "F.Cu" "F.Mask" "F.Paste")
			(net "GND")
			(options
				(clearance outline)
				(anchor circle)
			)
			(primitives
				(gr_poly
					(pts
						(arc
							(start 0.2032 -0.2286)
							(mid 0.275042 -0.198842)
							(end 0.3048 -0.127)
						)
						(arc
							(start 0.3048 0.127)
							(mid 0.275042 0.198842)
							(end 0.2032 0.2286)
						)
						(arc
							(start -0.2032 0.2286)
							(mid -0.275042 0.198842)
							(end -0.3048 0.127)
						)
						(arc
							(start -0.3048 -0.127)
							(mid -0.275042 -0.198842)
							(end -0.2032 -0.2286)
						)
					)
					(width 0)
					(fill yes)
				)
			)
		)
	)
	(footprint ""
		(layer "F.Cu")
		(at 208.055972 -75.0316 90)
		(property "Reference" "C309"
			(at 0 0 90)
			(layer "F.SilkS")
			(hide yes)
			(effects
				(font
					(size 1.27 1.27)
				)
			)
		)
		(property "Value" "SCD01U16V1KX-GP"
			(at -2.8321 -1.7399 90)
			(unlocked yes)
			(layer "F.Fab")
			(hide yes)
			(effects
				(font
					(size 1.016 1.016)
					(thickness 0.1524)
				)
			)
		)
		(property "Device Type" "C0201H13"
			(at -2.8321 -3.2639 90)
			(unlocked yes)
			(layer "F.Fab")
			(hide yes)
			(effects
				(font
					(size 1.016 1.016)
					(thickness 0.1524)
				)
			)
		)
		(duplicate_pad_numbers_are_jumpers no)
		(fp_rect
			(start -0.2794 0.6477)
			(end 0.2794 -0.6477)
			(stroke
				(width 0)
				(type default)
			)
			(fill no)
			(layer "F.CrtYd")
		)
		(fp_rect
			(start -0.2794 0.6477)
			(end 0.2794 -0.6477)
			(stroke
				(width 0)
				(type default)
			)
			(fill no)
			(layer "F.Fab")
		)
		(pad "1" smd custom
			(at 0 -0.2794 90)
			(size 0.0762 0.0762)
			(layers "F.Cu" "F.Mask" "F.Paste")
			(net "PHY_IOC_TO_CON_A_1_DP_C")
			(options
				(clearance outline)
				(anchor circle)
			)
			(primitives
				(gr_poly
					(pts
						(arc
							(start 0.1524 -0.127)
							(mid 0.137521 -0.162921)
							(end 0.1016 -0.1778)
						)
						(arc
							(start -0.1016 -0.1778)
							(mid -0.137521 -0.162921)
							(end -0.1524 -0.127)
						)
						(arc
							(start -0.1524 0.127)
							(mid -0.137521 0.162921)
							(end -0.1016 0.1778)
						)
						(arc
							(start 0.1016 0.1778)
							(mid 0.137521 0.162921)
							(end 0.1524 0.127)
						)
					)
					(width 0)
					(fill yes)
				)
			)
		)
		(pad "2" smd custom
			(at 0 0.2794 90)
			(size 0.0762 0.0762)
			(layers "F.Cu" "F.Mask" "F.Paste")
			(net "PHY_IOC_TO_CON_A_1_DP")
			(options
				(clearance outline)
				(anchor circle)
			)
			(primitives
				(gr_poly
					(pts
						(arc
							(start 0.1524 -0.127)
							(mid 0.137521 -0.162921)
							(end 0.1016 -0.1778)
						)
						(arc
							(start -0.1016 -0.1778)
							(mid -0.137521 -0.162921)
							(end -0.1524 -0.127)
						)
						(arc
							(start -0.1524 0.127)
							(mid -0.137521 0.162921)
							(end -0.1016 0.1778)
						)
						(arc
							(start 0.1016 0.1778)
							(mid 0.137521 0.162921)
							(end 0.1524 0.127)
						)
					)
					(width 0)
					(fill yes)
				)
			)
		)
	)
	(footprint ""
		(layer "F.Cu")
		(at 133.9088 -13.6144 -90)
		(property "Reference" "R442"
			(at 0 0 270)
			(layer "F.SilkS")
			(hide yes)
			(effects
				(font
					(size 1.27 1.27)
				)
			)
		)
		(property "Value" "10R2F-L-GP"
			(at 0.064008 -3.993896 270)
			(unlocked yes)
			(layer "F.Fab")
			(hide yes)
			(effects
				(font
					(size 1.016 1.016)
					(thickness 0.1524)
				)
			)
		)
		(property "Device Type" "R402H14"
			(at 0.064008 -5.517896 270)
			(unlocked yes)
			(layer "F.Fab")
			(hide yes)
			(effects
				(font
					(size 1.016 1.016)
					(thickness 0.1524)
				)
			)
		)
		(duplicate_pad_numbers_are_jumpers no)
		(fp_line
			(start -0.508 -0.9398)
			(end -0.508 0.9398)
			(stroke
				(width 0.1524)
				(type default)
			)
			(layer "F.SilkS")
		)
		(fp_line
			(start 0.508 -0.9398)
			(end -0.508 -0.9398)
			(stroke
				(width 0.1524)
				(type default)
			)
			(layer "F.SilkS")
		)
		(fp_rect
			(start -0.508 0.9398)
			(end 0.508 -0.9398)
			(stroke
				(width 0)
				(type default)
			)
			(fill no)
			(layer "F.CrtYd")
		)
		(fp_rect
			(start -0.508 0.9398)
			(end 0.508 -0.9398)
			(stroke
				(width 0)
				(type default)
			)
			(fill no)
			(layer "F.Fab")
		)
		(pad "1" smd custom
			(at 0 -0.4445 270)
			(size 0.1397 0.1397)
			(layers "F.Cu" "F.Mask" "F.Paste")
			(net "MB0_CM_SENSE_R1_P")
			(options
				(clearance outline)
				(anchor circle)
			)
			(primitives
				(gr_poly
					(pts
						(arc
							(start -0.1778 -0.2794)
							(mid -0.249642 -0.249642)
							(end -0.2794 -0.1778)
						)
						(arc
							(start -0.2794 0.1778)
							(mid -0.249642 0.249642)
							(end -0.1778 0.2794)
						)
						(arc
							(start 0.1778 0.2794)
							(mid 0.249642 0.249642)
							(end 0.2794 0.1778)
						)
						(arc
							(start 0.2794 -0.1778)
							(mid 0.249642 -0.249642)
							(end 0.1778 -0.2794)
						)
					)
					(width 0)
					(fill yes)
				)
			)
		)
		(pad "2" smd custom
			(at 0 0.4445 270)
			(size 0.1397 0.1397)
			(layers "F.Cu" "F.Mask" "F.Paste")
			(net "ADM1278_HS_P")
			(options
				(clearance outline)
				(anchor circle)
			)
			(primitives
				(gr_poly
					(pts
						(arc
							(start -0.1778 -0.2794)
							(mid -0.249642 -0.249642)
							(end -0.2794 -0.1778)
						)
						(arc
							(start -0.2794 0.1778)
							(mid -0.249642 0.249642)
							(end -0.1778 0.2794)
						)
						(arc
							(start 0.1778 0.2794)
							(mid 0.249642 0.249642)
							(end 0.2794 0.1778)
						)
						(arc
							(start 0.2794 -0.1778)
							(mid 0.249642 -0.249642)
							(end 0.1778 -0.2794)
						)
					)
					(width 0)
					(fill yes)
				)
			)
		)
	)
	(footprint ""
		(layer "F.Cu")
		(at 168.6306 -107.1118 -90)
		(property "Reference" "C464"
			(at 0 0 270)
			(layer "F.SilkS")
			(hide yes)
			(effects
				(font
					(size 1.27 1.27)
				)
			)
		)
		(property "Value" "SC1U16V2KX-7-GP"
			(at 1.7526 -1.6002 270)
			(unlocked yes)
			(layer "F.Fab")
			(hide yes)
			(effects
				(font
					(size 1.016 1.016)
					(thickness 0.1524)
				)
			)
		)
		(property "Device Type" "C402-TO0D2H24"
			(at 1.7526 -3.1242 270)
			(unlocked yes)
			(layer "F.Fab")
			(hide yes)
			(effects
				(font
					(size 1.016 1.016)
					(thickness 0.1524)
				)
			)
		)
		(duplicate_pad_numbers_are_jumpers no)
		(fp_rect
			(start -0.4826 0.889)
			(end 0.4826 -0.889)
			(stroke
				(width 0)
				(type default)
			)
			(fill no)
			(layer "F.CrtYd")
		)
		(fp_rect
			(start -0.4826 0.889)
			(end 0.4826 -0.889)
			(stroke
				(width 0)
				(type default)
			)
			(fill no)
			(layer "F.Fab")
		)
		(pad "1" smd custom
			(at 0 -0.4572 270)
			(size 0.1524 0.1524)
			(layers "F.Cu" "F.Mask" "F.Paste")
			(net "P1V8")
			(options
				(clearance outline)
				(anchor circle)
			)
			(primitives
				(gr_poly
					(pts
						(arc
							(start -0.254 0.3048)
							(mid -0.325842 0.275042)
							(end -0.3556 0.2032)
						)
						(arc
							(start -0.3556 -0.2032)
							(mid -0.325842 -0.275042)
							(end -0.254 -0.3048)
						)
						(arc
							(start 0.254 -0.3048)
							(mid 0.325842 -0.275042)
							(end 0.3556 -0.2032)
						)
						(arc
							(start 0.3556 0.2032)
							(mid 0.325842 0.275042)
							(end 0.254 0.3048)
						)
					)
					(width 0)
					(fill yes)
				)
			)
		)
		(pad "2" smd custom
			(at 0 0.4572 270)
			(size 0.1524 0.1524)
			(layers "F.Cu" "F.Mask" "F.Paste")
			(net "GND")
			(options
				(clearance outline)
				(anchor circle)
			)
			(primitives
				(gr_poly
					(pts
						(arc
							(start -0.254 0.3048)
							(mid -0.325842 0.275042)
							(end -0.3556 0.2032)
						)
						(arc
							(start -0.3556 -0.2032)
							(mid -0.325842 -0.275042)
							(end -0.254 -0.3048)
						)
						(arc
							(start 0.254 -0.3048)
							(mid 0.325842 -0.275042)
							(end 0.3556 -0.2032)
						)
						(arc
							(start 0.3556 0.2032)
							(mid 0.325842 0.275042)
							(end 0.254 0.3048)
						)
					)
					(width 0)
					(fill yes)
				)
			)
		)
	)
	(footprint ""
		(layer "F.Cu")
		(at 52.8574 -130.8608)
		(property "Reference" "TP12"
			(at 0 0 0)
			(layer "F.SilkS")
			(hide yes)
			(effects
				(font
					(size 1.27 1.27)
				)
			)
		)
		(property "Value" "TPAD28-2-GP"
			(at -0.0127 -1.6637 0)
			(unlocked yes)
			(layer "F.Fab")
			(hide yes)
			(effects
				(font
					(size 1.016 1.016)
					(thickness 0.1524)
				)
			)
		)
		(property "Device Type" "TPAD28"
			(at -0.0127 -3.1877 0)
			(unlocked yes)
			(layer "F.Fab")
			(hide yes)
			(effects
				(font
					(size 1.016 1.016)
					(thickness 0.1524)
				)
			)
		)
		(duplicate_pad_numbers_are_jumpers no)
		(fp_poly
			(pts
				(arc
					(start 0.3556 0)
					(mid -0.3556 0)
					(end 0.3556 0)
				)
			)
			(stroke
				(width 0)
				(type default)
			)
			(fill no)
			(layer "F.CrtYd")
		)
		(fp_poly
			(pts
				(arc
					(start 0.6096 0)
					(mid -0.6096 0)
					(end 0.6096 0)
				)
			)
			(stroke
				(width 0)
				(type default)
			)
			(fill no)
			(layer "F.Fab")
		)
		(pad "1" smd circle
			(at 0 0)
			(size 0.7112 0.7112)
			(layers "F.Cu" "F.Mask" "F.Paste")
			(net "TP_BMC0_LPC_LAD3")
		)
	)
)
